(kicad_pcb
	(version 20260206)
	(generator "pcbnew")
	(generator_version "10.0")
	(general
		(thickness 1.6)
		(legacy_teardrops no)
	)
	(paper "A4")
	(title_block
		(title "03242023_DA0F0TMBIJ0_F0T_Motherboard_J_brd_V01_OCP.brd")
		(comment 1 "Grand Teton / footprints 1066-1070 of 6105")
	)
	(layers
		(0 "F.Cu" signal "TOP")
		(4 "In1.Cu" signal "GND")
		(6 "In2.Cu" signal "IN1")
		(8 "In3.Cu" signal "GND1")
		(10 "In4.Cu" signal "IN2")
		(12 "In5.Cu" signal "GND2")
		(14 "In6.Cu" signal "IN3")
		(16 "In7.Cu" signal "GND3")
		(18 "In8.Cu" signal "VCC")
		(20 "In9.Cu" signal "VCC1")
		(22 "In10.Cu" signal "GND4")
		(24 "In11.Cu" signal "IN4")
		(26 "In12.Cu" signal "GND5")
		(28 "In13.Cu" signal "IN5")
		(30 "In14.Cu" signal "GND6")
		(32 "In15.Cu" signal "IN6")
		(34 "In16.Cu" signal "GND7")
		(2 "B.Cu" signal "BOTTOM")
		(9 "F.Adhes" user "F.Adhesive")
		(11 "B.Adhes" user "B.Adhesive")
		(13 "F.Paste" user "Package Geometry/Pastemask Top")
		(15 "B.Paste" user "Package Geometry/Pastemask Bottom")
		(5 "F.SilkS" user "Ref Des/Silkscreen Top")
		(7 "B.SilkS" user "Ref Des/Silkscreen Bottom")
		(1 "F.Mask" user "Board Geometry/Soldermask Top")
		(3 "B.Mask" user "Board Geometry/Soldermask Bottom")
		(17 "Dwgs.User" user "User.Drawings")
		(19 "Cmts.User" user "User.Comments")
		(21 "Eco1.User" user "User.Eco1")
		(23 "Eco2.User" user "User.Eco2")
		(25 "Edge.Cuts" user "Board Geometry/Outline")
		(27 "Margin" user)
		(31 "F.CrtYd" user "Package Geometry/Place Bound Top")
		(29 "B.CrtYd" user "Package Geometry/Place Bound Bottom")
		(35 "F.Fab" user "Ref Des/Assembly Top")
		(33 "B.Fab" user "Ref Des/Assembly Bottom")
	)
	(footprint ""
		(layer "F.Cu")
		(at 180.528468 -53.065934 180)
		(property "Reference" "C1105"
			(at 0 0 180)
			(layer "F.SilkS")
			(hide yes)
			(effects
				(font
					(size 1.27 1.27)
				)
			)
		)
		(property "Value" ""
			(at 0 0 180)
			(layer "F.Fab")
			(effects
				(font
					(size 1.27 1.27)
				)
			)
		)
		(duplicate_pad_numbers_are_jumpers no)
		(fp_line
			(start 0.299974 0.150114)
			(end -0.299974 0.150114)
			(stroke
				(width 0.1)
				(type default)
			)
			(layer "F.Fab")
		)
		(fp_line
			(start 0.299974 -0.150114)
			(end 0.299974 0.150114)
			(stroke
				(width 0.1)
				(type default)
			)
			(layer "F.Fab")
		)
		(fp_line
			(start -0.299974 0.150114)
			(end -0.299974 -0.150114)
			(stroke
				(width 0.1)
				(type default)
			)
			(layer "F.Fab")
		)
		(fp_line
			(start -0.299974 -0.150114)
			(end 0.299974 -0.150114)
			(stroke
				(width 0.1)
				(type default)
			)
			(layer "F.Fab")
		)
		(pad "1" smd rect
			(at -0.2667 0 180)
			(size 0.3048 0.381)
			(layers "F.Cu" "F.Mask" "F.Paste")
			(net "P3E_PCH_M2_TX_DN<0>")
		)
		(pad "2" smd rect
			(at 0.2667 0 180)
			(size 0.3048 0.381)
			(layers "F.Cu" "F.Mask" "F.Paste")
			(net "P3E_PCH_M2_TX_C_DN<0>")
		)
		(zone
			(layer "In1.Cu")
			(hatch none 0.5)
			(connect_pads
				(clearance 0)
			)
			(min_thickness 0.25)
			(keepout
				(tracks not_allowed)
				(vias allowed)
				(pads allowed)
				(copperpour not_allowed)
				(footprints allowed)
			)
			(placement
				(enabled no)
				(sheetname "")
			)
			(fill
				(thermal_gap 0.5)
				(thermal_bridge_width 0.5)
				(island_removal_mode 0)
			)
			(polygon
				(pts
					(arc
						(start 180.388768 -53.307234)
						(mid 180.44265 -53.284916)
						(end 180.464968 -53.231034)
					)
					(arc
						(start 180.464968 -52.900834)
						(mid 180.44265 -52.846952)
						(end 180.388768 -52.824634)
					)
					(arc
						(start 180.134768 -52.824634)
						(mid 180.080886 -52.846952)
						(end 180.058568 -52.900834)
					)
					(arc
						(start 180.058568 -53.231034)
						(mid 180.080886 -53.284916)
						(end 180.134768 -53.307234)
					)
				)
			)
		)
		(zone
			(layer "In1.Cu")
			(hatch none 0.5)
			(connect_pads
				(clearance 0)
			)
			(min_thickness 0.25)
			(keepout
				(tracks not_allowed)
				(vias allowed)
				(pads allowed)
				(copperpour not_allowed)
				(footprints allowed)
			)
			(placement
				(enabled no)
				(sheetname "")
			)
			(fill
				(thermal_gap 0.5)
				(thermal_bridge_width 0.5)
				(island_removal_mode 0)
			)
			(polygon
				(pts
					(arc
						(start 180.922168 -53.307234)
						(mid 180.97605 -53.284916)
						(end 180.998368 -53.231034)
					)
					(arc
						(start 180.998368 -52.900834)
						(mid 180.97605 -52.846952)
						(end 180.922168 -52.824634)
					)
					(arc
						(start 180.668168 -52.824634)
						(mid 180.614286 -52.846952)
						(end 180.591968 -52.900834)
					)
					(arc
						(start 180.591968 -53.231034)
						(mid 180.614286 -53.284916)
						(end 180.668168 -53.307234)
					)
				)
			)
		)
	)
	(footprint ""
		(layer "F.Cu")
		(at 120.129554 -402.371052 -90)
		(property "Reference" "C743"
			(at 0 0 270)
			(layer "F.SilkS")
			(hide yes)
			(effects
				(font
					(size 1.27 1.27)
				)
			)
		)
		(property "Value" ""
			(at 0 0 270)
			(layer "F.Fab")
			(effects
				(font
					(size 1.27 1.27)
				)
			)
		)
		(duplicate_pad_numbers_are_jumpers no)
		(fp_line
			(start -0.299974 0.150114)
			(end -0.299974 -0.150114)
			(stroke
				(width 0.1)
				(type default)
			)
			(layer "F.Fab")
		)
		(fp_line
			(start 0.299974 0.150114)
			(end -0.299974 0.150114)
			(stroke
				(width 0.1)
				(type default)
			)
			(layer "F.Fab")
		)
		(fp_line
			(start -0.299974 -0.150114)
			(end 0.299974 -0.150114)
			(stroke
				(width 0.1)
				(type default)
			)
			(layer "F.Fab")
		)
		(fp_line
			(start 0.299974 -0.150114)
			(end 0.299974 0.150114)
			(stroke
				(width 0.1)
				(type default)
			)
			(layer "F.Fab")
		)
		(pad "1" smd rect
			(at -0.2667 0 270)
			(size 0.3048 0.381)
			(layers "F.Cu" "F.Mask" "F.Paste")
			(net "P5E_CPU1_PE2_TX_C_DP<15>")
		)
		(pad "2" smd rect
			(at 0.2667 0 270)
			(size 0.3048 0.381)
			(layers "F.Cu" "F.Mask" "F.Paste")
			(net "P5E_CPU1_PE2_TX_DP<15>")
		)
	)
	(footprint ""
		(layer "F.Cu")
		(at 41.565068 -353.547934)
		(property "Reference" "PU78_P1_4"
			(at -13.965428 -4.667504 0)
			(unlocked yes)
			(layer "F.SilkS")
			(effects
				(font
					(size 0.7874 0.5842)
					(thickness 0.1524)
				)
				(justify left)
			)
		)
		(property "Value" ""
			(at 0 0 0)
			(layer "F.Fab")
			(effects
				(font
					(size 1.27 1.27)
				)
			)
		)
		(duplicate_pad_numbers_are_jumpers no)
		(fp_line
			(start -2.500122 -2.999994)
			(end -2.24409 -2.999994)
			(stroke
				(width 0.1524)
				(type default)
			)
			(layer "F.SilkS")
		)
		(fp_line
			(start -2.500122 -2.529078)
			(end -2.500122 -2.999994)
			(stroke
				(width 0.1524)
				(type default)
			)
			(layer "F.SilkS")
		)
		(fp_line
			(start -2.500122 0.6604)
			(end -2.500122 0.229108)
			(stroke
				(width 0.1524)
				(type default)
			)
			(layer "F.SilkS")
		)
		(fp_line
			(start -2.500122 2.999994)
			(end -2.500122 2.339594)
			(stroke
				(width 0.1524)
				(type default)
			)
			(layer "F.SilkS")
		)
		(fp_line
			(start -2.2987 2.999994)
			(end -2.500122 2.999994)
			(stroke
				(width 0.1524)
				(type default)
			)
			(layer "F.SilkS")
		)
		(fp_line
			(start 2.31394 -2.999994)
			(end 2.500122 -2.999994)
			(stroke
				(width 0.1524)
				(type default)
			)
			(layer "F.SilkS")
		)
		(fp_line
			(start 2.500122 -2.999994)
			(end 2.500122 -2.44348)
			(stroke
				(width 0.1524)
				(type default)
			)
			(layer "F.SilkS")
		)
		(fp_line
			(start 2.500122 2.339594)
			(end 2.500122 2.999994)
			(stroke
				(width 0.1524)
				(type default)
			)
			(layer "F.SilkS")
		)
		(fp_line
			(start 2.500122 2.999994)
			(end 2.2987 2.999994)
			(stroke
				(width 0.1524)
				(type default)
			)
			(layer "F.SilkS")
		)
		(fp_poly
			(pts
				(xy -5.457952 -2.871978) (xy -4.441952 -2.363978) (xy -5.457952 -1.855978)
			)
			(stroke
				(width 0)
				(type default)
			)
			(fill yes)
			(layer "F.SilkS")
		)
		(fp_line
			(start -2.500122 -2.999994)
			(end 2.500122 -2.999994)
			(stroke
				(width 0.1)
				(type default)
			)
			(layer "F.Fab")
		)
		(fp_line
			(start -2.500122 2.999994)
			(end -2.500122 -2.999994)
			(stroke
				(width 0.1)
				(type default)
			)
			(layer "F.Fab")
		)
		(fp_line
			(start 2.500122 -2.999994)
			(end 2.500122 2.999994)
			(stroke
				(width 0.1)
				(type default)
			)
			(layer "F.Fab")
		)
		(fp_line
			(start 2.500122 2.999994)
			(end -2.500122 2.999994)
			(stroke
				(width 0.1)
				(type default)
			)
			(layer "F.Fab")
		)
		(fp_poly
			(pts
				(xy -4.218432 -2.783078) (xy -4.218432 -1.767078) (xy -3.202432 -2.275078)
			)
			(stroke
				(width 0)
				(type default)
			)
			(fill yes)
			(layer "F.Fab")
		)
		(pad "1" smd rect
			(at -2.400046 -2.275078 90)
			(size 0.2286 0.6096)
			(layers "F.Cu" "F.Mask" "F.Paste")
			(net "PVCCFA_EHV_FIVRA_CPU1_VOS4")
		)
		(pad "2" smd rect
			(at -2.400046 -1.82499 90)
			(size 0.2286 0.6096)
			(layers "F.Cu" "F.Mask" "F.Paste")
			(net "GND")
		)
		(pad "3" smd rect
			(at -2.400046 -1.374902 90)
			(size 0.2286 0.6096)
			(layers "F.Cu" "F.Mask" "F.Paste")
			(net "PVCCFA_EHV_FIVRA_CPU1_VDD4")
		)
		(pad "4" smd rect
			(at -2.400046 -0.925068 90)
			(size 0.2286 0.6096)
			(layers "F.Cu" "F.Mask" "F.Paste")
			(net "PVCCFA_EHV_FIVRA_CPU1_PVCC2")
		)
		(pad "5" smd rect
			(at -2.400046 -0.47498 90)
			(size 0.2286 0.6096)
			(layers "F.Cu" "F.Mask" "F.Paste")
			(net "GND")
		)
		(pad "6" smd rect
			(at -2.400046 -0.024892 90)
			(size 0.2286 0.6096)
			(layers "F.Cu" "F.Mask" "F.Paste")
			(net "Net_8496")
		)
		(pad "7_9-20_24" smd circle
			(at 0 1.150112 90)
			(size 0 0)
			(layers "F.Cu" "F.Mask" "F.Paste")
			(net "GND")
		)
		(pad "10_19" smd rect
			(at 0 2.899918 90)
			(size 0.6096 4.318)
			(layers "F.Cu" "F.Mask" "F.Paste")
			(net "SW_PVCCFA_EHV_FIVRA_CPU1_SW4")
		)
		(pad "25_29" smd rect
			(at 1.549908 -1.279906 270)
			(size 2.0574 2.3114)
			(layers "F.Cu" "F.Mask" "F.Paste")
			(net "SW_P12V_PVCCFA_EHV_FIVRA_CPU1_L")
		)
		(pad "30" smd rect
			(at 2.05994 -2.899918)
			(size 0.2286 0.6096)
			(layers "F.Cu" "F.Mask" "F.Paste")
			(net "SW_P12V_PVCCFA_EHV_FIVRA_CPU1_L")
		)
		(pad "31" smd rect
			(at 1.610106 -2.899918)
			(size 0.2286 0.6096)
			(layers "F.Cu" "F.Mask" "F.Paste")
			(net "Net_8497")
		)
		(pad "32" smd rect
			(at 1.160018 -2.899918)
			(size 0.2286 0.6096)
			(layers "F.Cu" "F.Mask" "F.Paste")
			(net "SW_PVCCFA_EHV_FIVRA_CPU1_BOOTR4")
		)
		(pad "33" smd rect
			(at 0.70993 -2.899918)
			(size 0.2286 0.6096)
			(layers "F.Cu" "F.Mask" "F.Paste")
			(net "SW_PVCCFA_EHV_FIVRA_CPU1_BOOT4")
		)
		(pad "34" smd rect
			(at 0.260096 -2.899918)
			(size 0.2286 0.6096)
			(layers "F.Cu" "F.Mask" "F.Paste")
			(net "PVCCFA_EHV_FIVRA_CPU1_PWM4")
		)
		(pad "35" smd rect
			(at -0.189992 -2.899918)
			(size 0.2286 0.6096)
			(layers "F.Cu" "F.Mask" "F.Paste")
			(net "PVCCFA_EHV_FIVRA_CPU1_VDD4")
		)
		(pad "36" smd rect
			(at -0.64008 -2.899918)
			(size 0.2286 0.6096)
			(layers "F.Cu" "F.Mask" "F.Paste")
			(net "PVCCFA_EHV_FIVRA_CPU1_BTSEN")
		)
		(pad "37" smd rect
			(at -1.089914 -2.899918)
			(size 0.2286 0.6096)
			(layers "F.Cu" "F.Mask" "F.Paste")
			(net "PVCCFA_EHV_FIVRA_CPU1_LSET4")
		)
		(pad "38" smd rect
			(at -1.540002 -2.899918)
			(size 0.2286 0.6096)
			(layers "F.Cu" "F.Mask" "F.Paste")
			(net "PVCCFA_EHV_FIVRA_CPU1_IMON4")
		)
		(pad "39" smd rect
			(at -1.99009 -2.899918)
			(size 0.2286 0.6096)
			(layers "F.Cu" "F.Mask" "F.Paste")
			(net "PVCCIN_CPU1_VREF")
		)
		(pad "40" smd rect
			(at -0.87503 -1.27508)
			(size 1.7526 1.9558)
			(layers "F.Cu" "F.Mask" "F.Paste")
			(net "GND")
		)
		(pad "41" smd rect
			(at -1.525016 0.249936 270)
			(size 0.3048 0.4572)
			(layers "F.Cu" "F.Mask" "F.Paste")
			(net "Net_8495")
		)
		(zone
			(layer "F.Cu")
			(hatch none 0.5)
			(connect_pads
				(clearance 0)
			)
			(min_thickness 0.25)
			(keepout
				(tracks not_allowed)
				(vias allowed)
				(pads allowed)
				(copperpour not_allowed)
				(footprints allowed)
			)
			(placement
				(enabled no)
				(sheetname "")
			)
			(fill
				(thermal_gap 0.5)
				(thermal_bridge_width 0.5)
				(island_removal_mode 0)
			)
			(polygon
				(pts
					(xy 39.064946 -350.54794) (xy 39.064946 -351.267268) (xy 44.06519 -351.267268) (xy 44.06519 -350.54794)
					(xy 43.774868 -350.54794) (xy 43.774868 -351.003616) (xy 39.355268 -351.003616) (xy 39.355268 -350.54794)
				)
			)
		)
		(zone
			(layer "F.Cu")
			(hatch none 0.5)
			(connect_pads
				(clearance 0)
			)
			(min_thickness 0.25)
			(keepout
				(tracks not_allowed)
				(vias allowed)
				(pads allowed)
				(copperpour not_allowed)
				(footprints allowed)
			)
			(placement
				(enabled no)
				(sheetname "")
			)
			(fill
				(thermal_gap 0.5)
				(thermal_bridge_width 0.5)
				(island_removal_mode 0)
			)
			(polygon
				(pts
					(xy 39.520622 -353.794568) (xy 39.762938 -353.794568) (xy 39.762938 -353.794314) (xy 40.54602 -353.794314)
					(xy 40.54602 -353.438968) (xy 40.614346 -353.438968) (xy 40.614346 -352.86696) (xy 40.54602 -352.798634)
					(xy 39.064946 -352.798634) (xy 39.064946 -353.255326) (xy 39.760652 -353.255326) (xy 39.760652 -353.094798)
					(xy 40.319452 -353.094798) (xy 40.319452 -353.501198) (xy 39.760652 -353.501198) (xy 39.760652 -353.280726)
					(xy 39.064946 -353.280726) (xy 39.064946 -353.407726) (xy 39.520622 -353.407726)
				)
			)
		)
	)
	(footprint ""
		(layer "F.Cu")
		(at 44.169584 -112.619282)
		(property "Reference" "R1800"
			(at 0 0 0)
			(layer "F.SilkS")
			(hide yes)
			(effects
				(font
					(size 1.27 1.27)
				)
			)
		)
		(property "Value" ""
			(at 0 0 0)
			(layer "F.Fab")
			(effects
				(font
					(size 1.27 1.27)
				)
			)
		)
		(duplicate_pad_numbers_are_jumpers no)
		(fp_line
			(start -0.7874 -0.4064)
			(end 0.7874 -0.4064)
			(stroke
				(width 0.1524)
				(type default)
			)
			(layer "F.SilkS")
		)
		(fp_line
			(start -0.7874 0.4064)
			(end -0.7874 -0.4064)
			(stroke
				(width 0.1524)
				(type default)
			)
			(layer "F.SilkS")
		)
		(fp_line
			(start 0.7874 -0.4064)
			(end 0.7874 0.4064)
			(stroke
				(width 0.1524)
				(type default)
			)
			(layer "F.SilkS")
		)
		(fp_line
			(start 0.7874 0.4064)
			(end -0.7874 0.4064)
			(stroke
				(width 0.1524)
				(type default)
			)
			(layer "F.SilkS")
		)
		(fp_line
			(start -0.67945 -0.305054)
			(end -0.12065 -0.305054)
			(stroke
				(width 0.1)
				(type default)
			)
			(layer "F.Fab")
		)
		(fp_line
			(start -0.67945 0.3048)
			(end -0.67945 -0.305054)
			(stroke
				(width 0.1)
				(type default)
			)
			(layer "F.Fab")
		)
		(fp_line
			(start -0.12065 -0.305054)
			(end -0.12065 -0.2794)
			(stroke
				(width 0.1)
				(type default)
			)
			(layer "F.Fab")
		)
		(fp_line
			(start -0.12065 -0.2794)
			(end 0.12065 -0.2794)
			(stroke
				(width 0.1)
				(type default)
			)
			(layer "F.Fab")
		)
		(fp_line
			(start -0.12065 0.2794)
			(end -0.12065 0.3048)
			(stroke
				(width 0.1)
				(type default)
			)
			(layer "F.Fab")
		)
		(fp_line
			(start -0.12065 0.3048)
			(end -0.67945 0.3048)
			(stroke
				(width 0.1)
				(type default)
			)
			(layer "F.Fab")
		)
		(fp_line
			(start 0.120396 0.2794)
			(end -0.12065 0.2794)
			(stroke
				(width 0.1)
				(type default)
			)
			(layer "F.Fab")
		)
		(fp_line
			(start 0.120396 0.3048)
			(end 0.120396 0.2794)
			(stroke
				(width 0.1)
				(type default)
			)
			(layer "F.Fab")
		)
		(fp_line
			(start 0.12065 -0.3048)
			(end 0.67945 -0.3048)
			(stroke
				(width 0.1)
				(type default)
			)
			(layer "F.Fab")
		)
		(fp_line
			(start 0.12065 -0.2794)
			(end 0.12065 -0.3048)
			(stroke
				(width 0.1)
				(type default)
			)
			(layer "F.Fab")
		)
		(fp_line
			(start 0.67945 -0.3048)
			(end 0.67945 0.3048)
			(stroke
				(width 0.1)
				(type default)
			)
			(layer "F.Fab")
		)
		(fp_line
			(start 0.67945 0.3048)
			(end 0.120396 0.3048)
			(stroke
				(width 0.1)
				(type default)
			)
			(layer "F.Fab")
		)
		(pad "1" smd circle
			(at -0.40005 0)
			(size 0 0)
			(layers "F.Cu" "F.Mask" "F.Paste")
			(net "P12V_AUX_ADC")
		)
		(pad "2" smd circle
			(at 0.40005 0)
			(size 0 0)
			(layers "F.Cu" "F.Mask" "F.Paste")
			(net "GND")
		)
	)
	(footprint ""
		(layer "F.Cu")
		(at 415.818828 -165.760654 180)
		(property "Reference" "PC2948"
			(at 0 0 180)
			(layer "F.SilkS")
			(hide yes)
			(effects
				(font
					(size 1.27 1.27)
				)
			)
		)
		(property "Value" ""
			(at 0 0 180)
			(layer "F.Fab")
			(effects
				(font
					(size 1.27 1.27)
				)
			)
		)
		(duplicate_pad_numbers_are_jumpers no)
		(fp_line
			(start 0.7874 0.4064)
			(end -0.7874 0.4064)
			(stroke
				(width 0.1524)
				(type default)
			)
			(layer "F.SilkS")
		)
		(fp_line
			(start 0.7874 -0.4064)
			(end 0.7874 0.4064)
			(stroke
				(width 0.1524)
				(type default)
			)
			(layer "F.SilkS")
		)
		(fp_line
			(start -0.7874 0.4064)
			(end -0.7874 -0.4064)
			(stroke
				(width 0.1524)
				(type default)
			)
			(layer "F.SilkS")
		)
		(fp_line
			(start -0.7874 -0.4064)
			(end 0.7874 -0.4064)
			(stroke
				(width 0.1524)
				(type default)
			)
			(layer "F.SilkS")
		)
		(fp_line
			(start 0.67945 0.3048)
			(end 0.120396 0.3048)
			(stroke
				(width 0.1)
				(type default)
			)
			(layer "F.Fab")
		)
		(fp_line
			(start 0.67945 -0.3048)
			(end 0.67945 0.3048)
			(stroke
				(width 0.1)
				(type default)
			)
			(layer "F.Fab")
		)
		(fp_line
			(start 0.12065 -0.2794)
			(end 0.12065 -0.3048)
			(stroke
				(width 0.1)
				(type default)
			)
			(layer "F.Fab")
		)
		(fp_line
			(start 0.12065 -0.3048)
			(end 0.67945 -0.3048)
			(stroke
				(width 0.1)
				(type default)
			)
			(layer "F.Fab")
		)
		(fp_line
			(start 0.120396 0.3048)
			(end 0.120396 0.2794)
			(stroke
				(width 0.1)
				(type default)
			)
			(layer "F.Fab")
		)
		(fp_line
			(start 0.120396 0.2794)
			(end -0.12065 0.2794)
			(stroke
				(width 0.1)
				(type default)
			)
			(layer "F.Fab")
		)
		(fp_line
			(start -0.12065 0.3048)
			(end -0.67945 0.3048)
			(stroke
				(width 0.1)
				(type default)
			)
			(layer "F.Fab")
		)
		(fp_line
			(start -0.12065 0.2794)
			(end -0.12065 0.3048)
			(stroke
				(width 0.1)
				(type default)
			)
			(layer "F.Fab")
		)
		(fp_line
			(start -0.12065 -0.2794)
			(end 0.12065 -0.2794)
			(stroke
				(width 0.1)
				(type default)
			)
			(layer "F.Fab")
		)
		(fp_line
			(start -0.12065 -0.305054)
			(end -0.12065 -0.2794)
			(stroke
				(width 0.1)
				(type default)
			)
			(layer "F.Fab")
		)
		(fp_line
			(start -0.67945 0.3048)
			(end -0.67945 -0.305054)
			(stroke
				(width 0.1)
				(type default)
			)
			(layer "F.Fab")
		)
		(fp_line
			(start -0.67945 -0.305054)
			(end -0.12065 -0.305054)
			(stroke
				(width 0.1)
				(type default)
			)
			(layer "F.Fab")
		)
		(pad "1" smd circle
			(at -0.40005 0 180)
			(size 0 0)
			(layers "F.Cu" "F.Mask" "F.Paste")
			(net "PVCCFA_EHV_CPU0_PVCC")
		)
		(pad "2" smd circle
			(at 0.40005 0 180)
			(size 0 0)
			(layers "F.Cu" "F.Mask" "F.Paste")
			(net "GND")
		)
	)
)
